(kicad_pcb
	(version 20260206)
	(generator "pcbnew")
	(generator_version "10.0")
	(general
		(thickness 1.6)
		(legacy_teardrops no)
	)
	(paper "A4")
	(title_block
		(title "fcb — Lightning_FCB_BRD.brd")
		(comment 1 "Lightning (Wiwynn / Facebook NVMe JBOF) / footprints 400-403 of 495")
	)
	(layers
		(0 "F.Cu" signal "TOP")
		(4 "In1.Cu" signal "L2GND")
		(6 "In2.Cu" signal "L3VCC")
		(2 "B.Cu" signal "BOTTOM")
		(9 "F.Adhes" user "F.Adhesive")
		(11 "B.Adhes" user "B.Adhesive")
		(13 "F.Paste" user "Package Geometry/Pastemask Top")
		(15 "B.Paste" user "Package Geometry/Pastemask Bottom")
		(5 "F.SilkS" user "Ref Des/Silkscreen Top")
		(7 "B.SilkS" user "Ref Des/Silkscreen Bottom")
		(1 "F.Mask" user "Board Geometry/Soldermask Top")
		(3 "B.Mask" user "Board Geometry/Soldermask Bottom")
		(17 "Dwgs.User" user "User.Drawings")
		(19 "Cmts.User" user "User.Comments")
		(21 "Eco1.User" user "User.Eco1")
		(23 "Eco2.User" user "User.Eco2")
		(25 "Edge.Cuts" user "Board Geometry/Outline")
		(27 "Margin" user)
		(31 "F.CrtYd" user "Package Geometry/Place Bound Top")
		(29 "B.CrtYd" user "Package Geometry/Place Bound Bottom")
		(35 "F.Fab" user "Ref Des/Assembly Top")
		(33 "B.Fab" user "Ref Des/Assembly Bottom")
	)
	(footprint ""
		(layer "F.Cu")
		(at 22.352 -186.2836 -90)
		(property "Reference" "R81"
			(at 0 0 270)
			(layer "F.SilkS")
			(hide yes)
			(effects
				(font
					(size 1.27 1.27)
				)
			)
		)
		(property "Value" "4K7R2F-GP"
			(at 0.064008 -3.993896 270)
			(unlocked yes)
			(layer "F.Fab")
			(hide yes)
			(effects
				(font
					(size 1.016 1.016)
					(thickness 0.1524)
				)
			)
		)
		(property "Device Type" "R402H16"
			(at 0.064008 -5.517896 270)
			(unlocked yes)
			(layer "F.Fab")
			(hide yes)
			(effects
				(font
					(size 1.016 1.016)
					(thickness 0.1524)
				)
			)
		)
		(duplicate_pad_numbers_are_jumpers no)
		(fp_line
			(start -0.508 -0.9398)
			(end -0.508 0.9398)
			(stroke
				(width 0.1524)
				(type default)
			)
			(layer "F.SilkS")
		)
		(fp_line
			(start 0.508 -0.9398)
			(end -0.508 -0.9398)
			(stroke
				(width 0.1524)
				(type default)
			)
			(layer "F.SilkS")
		)
		(fp_rect
			(start -0.508 0.9398)
			(end 0.508 -0.9398)
			(stroke
				(width 0)
				(type default)
			)
			(fill no)
			(layer "F.CrtYd")
		)
		(fp_rect
			(start -0.508 0.9398)
			(end 0.508 -0.9398)
			(stroke
				(width 0)
				(type default)
			)
			(fill no)
			(layer "F.Fab")
		)
		(pad "1" smd custom
			(at 0 -0.4445 270)
			(size 0.1397 0.1397)
			(layers "F.Cu" "F.Mask" "F.Paste")
			(net "P12V")
			(options
				(clearance outline)
				(anchor circle)
			)
			(primitives
				(gr_poly
					(pts
						(arc
							(start -0.1778 -0.2794)
							(mid -0.249642 -0.249642)
							(end -0.2794 -0.1778)
						)
						(arc
							(start -0.2794 0.1778)
							(mid -0.249642 0.249642)
							(end -0.1778 0.2794)
						)
						(arc
							(start 0.1778 0.2794)
							(mid 0.249642 0.249642)
							(end 0.2794 0.1778)
						)
						(arc
							(start 0.2794 -0.1778)
							(mid 0.249642 -0.249642)
							(end 0.1778 -0.2794)
						)
					)
					(width 0)
					(fill yes)
				)
			)
		)
		(pad "2" smd custom
			(at 0 0.4445 270)
			(size 0.1397 0.1397)
			(layers "F.Cu" "F.Mask" "F.Paste")
			(net "FAN_TACH8")
			(options
				(clearance outline)
				(anchor circle)
			)
			(primitives
				(gr_poly
					(pts
						(arc
							(start -0.1778 -0.2794)
							(mid -0.249642 -0.249642)
							(end -0.2794 -0.1778)
						)
						(arc
							(start -0.2794 0.1778)
							(mid -0.249642 0.249642)
							(end -0.1778 0.2794)
						)
						(arc
							(start 0.1778 0.2794)
							(mid 0.249642 0.249642)
							(end 0.2794 0.1778)
						)
						(arc
							(start 0.2794 -0.1778)
							(mid 0.249642 -0.249642)
							(end 0.1778 -0.2794)
						)
					)
					(width 0)
					(fill yes)
				)
			)
		)
	)
	(footprint ""
		(layer "F.Cu")
		(at 34.2138 -356.185216)
		(property "Reference" "R365"
			(at 0 0 0)
			(layer "F.SilkS")
			(hide yes)
			(effects
				(font
					(size 1.27 1.27)
				)
			)
		)
		(property "Value" "10MR2J-L-GP"
			(at 0.064008 -3.993896 0)
			(unlocked yes)
			(layer "F.Fab")
			(hide yes)
			(effects
				(font
					(size 1.016 1.016)
					(thickness 0.1524)
				)
			)
		)
		(property "Device Type" "R402H16"
			(at 0.064008 -5.517896 0)
			(unlocked yes)
			(layer "F.Fab")
			(hide yes)
			(effects
				(font
					(size 1.016 1.016)
					(thickness 0.1524)
				)
			)
		)
		(duplicate_pad_numbers_are_jumpers no)
		(fp_line
			(start -0.508 -0.9398)
			(end -0.508 0.9398)
			(stroke
				(width 0.1524)
				(type default)
			)
			(layer "F.SilkS")
		)
		(fp_line
			(start 0.508 -0.9398)
			(end -0.508 -0.9398)
			(stroke
				(width 0.1524)
				(type default)
			)
			(layer "F.SilkS")
		)
		(fp_rect
			(start -0.508 0.9398)
			(end 0.508 -0.9398)
			(stroke
				(width 0)
				(type default)
			)
			(fill no)
			(layer "F.CrtYd")
		)
		(fp_rect
			(start -0.508 0.9398)
			(end 0.508 -0.9398)
			(stroke
				(width 0)
				(type default)
			)
			(fill no)
			(layer "F.Fab")
		)
		(pad "1" smd custom
			(at 0 -0.4445)
			(size 0.1397 0.1397)
			(layers "F.Cu" "F.Mask" "F.Paste")
			(net "OTP_RETRY_G")
			(options
				(clearance outline)
				(anchor circle)
			)
			(primitives
				(gr_poly
					(pts
						(arc
							(start -0.1778 -0.2794)
							(mid -0.249642 -0.249642)
							(end -0.2794 -0.1778)
						)
						(arc
							(start -0.2794 0.1778)
							(mid -0.249642 0.249642)
							(end -0.1778 0.2794)
						)
						(arc
							(start 0.1778 0.2794)
							(mid 0.249642 0.249642)
							(end 0.2794 0.1778)
						)
						(arc
							(start 0.2794 -0.1778)
							(mid 0.249642 -0.249642)
							(end 0.1778 -0.2794)
						)
					)
					(width 0)
					(fill yes)
				)
			)
		)
		(pad "2" smd custom
			(at 0 0.4445)
			(size 0.1397 0.1397)
			(layers "F.Cu" "F.Mask" "F.Paste")
			(net "GND")
			(options
				(clearance outline)
				(anchor circle)
			)
			(primitives
				(gr_poly
					(pts
						(arc
							(start -0.1778 -0.2794)
							(mid -0.249642 -0.249642)
							(end -0.2794 -0.1778)
						)
						(arc
							(start -0.2794 0.1778)
							(mid -0.249642 0.249642)
							(end -0.1778 0.2794)
						)
						(arc
							(start 0.1778 0.2794)
							(mid 0.249642 0.249642)
							(end 0.2794 0.1778)
						)
						(arc
							(start 0.2794 -0.1778)
							(mid 0.249642 -0.249642)
							(end 0.1778 -0.2794)
						)
					)
					(width 0)
					(fill yes)
				)
			)
		)
	)
	(footprint ""
		(layer "F.Cu")
		(at 8.001 -417.9062 180)
		(property "Reference" "Q7"
			(at 0 0 180)
			(layer "F.SilkS")
			(hide yes)
			(effects
				(font
					(size 1.27 1.27)
				)
			)
		)
		(property "Value" "PMBS3904-1-GP"
			(at 0 -9.0932 180)
			(unlocked yes)
			(layer "F.Fab")
			(hide yes)
			(effects
				(font
					(size 1.016 1.016)
					(thickness 0.1524)
				)
			)
		)
		(property "Device Type" "SOT-23-10H44"
			(at 0 -10.6172 180)
			(unlocked yes)
			(layer "F.Fab")
			(hide yes)
			(effects
				(font
					(size 1.016 1.016)
					(thickness 0.1524)
				)
			)
		)
		(duplicate_pad_numbers_are_jumpers no)
		(fp_line
			(start 1.651 1.778)
			(end 1.651 -1.778)
			(stroke
				(width 0.1524)
				(type default)
			)
			(layer "F.SilkS")
		)
		(fp_line
			(start 1.651 -1.778)
			(end -1.651 -1.778)
			(stroke
				(width 0.1524)
				(type default)
			)
			(layer "F.SilkS")
		)
		(fp_line
			(start -0.635 1.8796)
			(end -1.7526 1.8796)
			(stroke
				(width 0.3302)
				(type default)
			)
			(layer "F.SilkS")
		)
		(fp_line
			(start -0.71628 2.15265)
			(end -1.26492 2.15265)
			(stroke
				(width 0.0127)
				(type default)
			)
			(layer "F.SilkS")
		)
		(fp_line
			(start -0.719074 2.145538)
			(end -1.265936 2.14122)
			(stroke
				(width 0.0127)
				(type default)
			)
			(layer "F.SilkS")
		)
		(fp_line
			(start -0.9906 1.86309)
			(end -0.701294 2.15265)
			(stroke
				(width 0.0127)
				(type default)
			)
			(layer "F.SilkS")
		)
		(fp_line
			(start -0.994156 1.8669)
			(end -0.987044 1.8669)
			(stroke
				(width 0.0127)
				(type default)
			)
			(layer "F.SilkS")
		)
		(fp_line
			(start -1.003808 1.876552)
			(end -0.977646 1.876552)
			(stroke
				(width 0.0127)
				(type default)
			)
			(layer "F.SilkS")
		)
		(fp_line
			(start -1.013206 1.88595)
			(end -0.967994 1.88595)
			(stroke
				(width 0.0127)
				(type default)
			)
			(layer "F.SilkS")
		)
		(fp_line
			(start -1.022858 1.895602)
			(end -0.958596 1.895602)
			(stroke
				(width 0.0127)
				(type default)
			)
			(layer "F.SilkS")
		)
		(fp_line
			(start -1.032256 1.905)
			(end -0.948944 1.905)
			(stroke
				(width 0.0127)
				(type default)
			)
			(layer "F.SilkS")
		)
		(fp_line
			(start -1.041908 1.914652)
			(end -0.939546 1.914652)
			(stroke
				(width 0.0127)
				(type default)
			)
			(layer "F.SilkS")
		)
		(fp_line
			(start -1.051306 1.92405)
			(end -0.929894 1.92405)
			(stroke
				(width 0.0127)
				(type default)
			)
			(layer "F.SilkS")
		)
		(fp_line
			(start -1.060958 1.933702)
			(end -0.920496 1.933702)
			(stroke
				(width 0.0127)
				(type default)
			)
			(layer "F.SilkS")
		)
		(fp_line
			(start -1.070356 1.9431)
			(end -0.910844 1.9431)
			(stroke
				(width 0.0127)
				(type default)
			)
			(layer "F.SilkS")
		)
		(fp_line
			(start -1.080008 1.952752)
			(end -0.901446 1.952752)
			(stroke
				(width 0.0127)
				(type default)
			)
			(layer "F.SilkS")
		)
		(fp_line
			(start -1.089406 1.96215)
			(end -0.891794 1.96215)
			(stroke
				(width 0.0127)
				(type default)
			)
			(layer "F.SilkS")
		)
		(fp_line
			(start -1.099058 1.971802)
			(end -0.882396 1.971802)
			(stroke
				(width 0.0127)
				(type default)
			)
			(layer "F.SilkS")
		)
		(fp_line
			(start -1.108456 1.9812)
			(end -0.872744 1.9812)
			(stroke
				(width 0.0127)
				(type default)
			)
			(layer "F.SilkS")
		)
		(fp_line
			(start -1.118108 1.990852)
			(end -0.863346 1.990852)
			(stroke
				(width 0.0127)
				(type default)
			)
			(layer "F.SilkS")
		)
		(fp_line
			(start -1.127506 2.00025)
			(end -0.853694 2.00025)
			(stroke
				(width 0.0127)
				(type default)
			)
			(layer "F.SilkS")
		)
		(fp_line
			(start -1.137158 2.009902)
			(end -0.844296 2.009902)
			(stroke
				(width 0.0127)
				(type default)
			)
			(layer "F.SilkS")
		)
		(fp_line
			(start -1.146556 2.0193)
			(end -0.834644 2.0193)
			(stroke
				(width 0.0127)
				(type default)
			)
			(layer "F.SilkS")
		)
		(fp_line
			(start -1.156208 2.028952)
			(end -0.825246 2.028952)
			(stroke
				(width 0.0127)
				(type default)
			)
			(layer "F.SilkS")
		)
		(fp_line
			(start -1.165606 2.03835)
			(end -0.815594 2.03835)
			(stroke
				(width 0.0127)
				(type default)
			)
			(layer "F.SilkS")
		)
		(fp_line
			(start -1.175258 2.048002)
			(end -0.806196 2.048002)
			(stroke
				(width 0.0127)
				(type default)
			)
			(layer "F.SilkS")
		)
		(fp_line
			(start -1.184656 2.0574)
			(end -0.796544 2.0574)
			(stroke
				(width 0.0127)
				(type default)
			)
			(layer "F.SilkS")
		)
		(fp_line
			(start -1.194308 2.067052)
			(end -0.787146 2.067052)
			(stroke
				(width 0.0127)
				(type default)
			)
			(layer "F.SilkS")
		)
		(fp_line
			(start -1.203706 2.07645)
			(end -0.777494 2.07645)
			(stroke
				(width 0.0127)
				(type default)
			)
			(layer "F.SilkS")
		)
		(fp_line
			(start -1.213358 2.086102)
			(end -0.768096 2.086102)
			(stroke
				(width 0.0127)
				(type default)
			)
			(layer "F.SilkS")
		)
		(fp_line
			(start -1.222756 2.0955)
			(end -0.758444 2.0955)
			(stroke
				(width 0.0127)
				(type default)
			)
			(layer "F.SilkS")
		)
		(fp_line
			(start -1.232408 2.105152)
			(end -0.749046 2.105152)
			(stroke
				(width 0.0127)
				(type default)
			)
			(layer "F.SilkS")
		)
		(fp_line
			(start -1.241806 2.11455)
			(end -0.739394 2.11455)
			(stroke
				(width 0.0127)
				(type default)
			)
			(layer "F.SilkS")
		)
		(fp_line
			(start -1.251458 2.124202)
			(end -0.729996 2.124202)
			(stroke
				(width 0.0127)
				(type default)
			)
			(layer "F.SilkS")
		)
		(fp_line
			(start -1.260856 2.1336)
			(end -0.720344 2.1336)
			(stroke
				(width 0.0127)
				(type default)
			)
			(layer "F.SilkS")
		)
		(fp_line
			(start -1.279144 2.15265)
			(end -0.701294 2.15265)
			(stroke
				(width 0.0127)
				(type default)
			)
			(layer "F.SilkS")
		)
		(fp_line
			(start -1.279398 2.152142)
			(end -0.9906 1.86309)
			(stroke
				(width 0.0127)
				(type default)
			)
			(layer "F.SilkS")
		)
		(fp_line
			(start -1.651 1.778)
			(end 1.651 1.778)
			(stroke
				(width 0.1524)
				(type default)
			)
			(layer "F.SilkS")
		)
		(fp_line
			(start -1.651 -1.778)
			(end -1.651 1.778)
			(stroke
				(width 0.1524)
				(type default)
			)
			(layer "F.SilkS")
		)
		(fp_line
			(start -1.7526 1.8796)
			(end -1.7526 0.9906)
			(stroke
				(width 0.3302)
				(type default)
			)
			(layer "F.SilkS")
		)
		(fp_poly
			(pts
				(xy -1.285748 2.159) (xy -1.285748 1.8796) (xy -1.778 1.8796) (xy -1.778 -1.8796) (xy 1.778 -1.8796)
				(xy 1.778 1.8796) (xy -0.694944 1.8796) (xy -0.694944 2.159)
			)
			(stroke
				(width 0)
				(type default)
			)
			(fill no)
			(layer "F.CrtYd")
		)
		(fp_poly
			(pts
				(xy -1.285748 2.159) (xy -1.285748 1.8796) (xy -1.778 1.8796) (xy -1.778 -1.8796) (xy 1.778 -1.8796)
				(xy 1.778 1.8796) (xy -0.694944 1.8796) (xy -0.694944 2.159)
			)
			(stroke
				(width 0)
				(type default)
			)
			(fill no)
			(layer "F.Fab")
		)
		(pad "1" smd rect
			(at -0.98425 0.9525 180)
			(size 0.762 1.143)
			(layers "F.Cu" "F.Mask" "F.Paste")
			(net "LED_DR_LED1_B")
		)
		(pad "2" smd rect
			(at 0.98425 0.9525 180)
			(size 0.762 1.143)
			(layers "F.Cu" "F.Mask" "F.Paste")
			(net "GND")
		)
		(pad "3" smd rect
			(at 0 -0.9525 180)
			(size 0.762 1.143)
			(layers "F.Cu" "F.Mask" "F.Paste")
			(net "LED_DR_LED1_BLUE")
		)
	)
	(footprint ""
		(layer "F.Cu")
		(at 26.416 -410.591)
		(property "Reference" "PR30"
			(at 0 0 0)
			(layer "F.SilkS")
			(hide yes)
			(effects
				(font
					(size 1.27 1.27)
				)
			)
		)
		(property "Value" "D0005RL1632F-GP-U"
			(at 3.2258 1.2954 0)
			(unlocked yes)
			(layer "F.Fab")
			(hide yes)
			(effects
				(font
					(size 1.016 1.016)
					(thickness 0.1524)
				)
			)
		)
		(property "Device Type" "RL3115-4PH45"
			(at 3.2258 -0.2286 0)
			(unlocked yes)
			(layer "F.Fab")
			(hide yes)
			(effects
				(font
					(size 1.016 1.016)
					(thickness 0.1524)
				)
			)
		)
		(duplicate_pad_numbers_are_jumpers no)
		(fp_line
			(start -2.0574 -1.7653)
			(end -2.0574 -0.4064)
			(stroke
				(width 0.3302)
				(type default)
			)
			(layer "F.SilkS")
		)
		(fp_line
			(start -1.9685 -1.651)
			(end 1.9685 -1.651)
			(stroke
				(width 0.1524)
				(type default)
			)
			(layer "F.SilkS")
		)
		(fp_line
			(start -1.9685 1.651)
			(end -1.9685 -1.651)
			(stroke
				(width 0.1524)
				(type default)
			)
			(layer "F.SilkS")
		)
		(fp_line
			(start -0.5334 -1.7653)
			(end -2.0574 -1.7653)
			(stroke
				(width 0.3302)
				(type default)
			)
			(layer "F.SilkS")
		)
		(fp_line
			(start 1.9685 -1.651)
			(end 1.9685 1.651)
			(stroke
				(width 0.1524)
				(type default)
			)
			(layer "F.SilkS")
		)
		(fp_line
			(start 1.9685 1.651)
			(end -1.9685 1.651)
			(stroke
				(width 0.1524)
				(type default)
			)
			(layer "F.SilkS")
		)
		(fp_poly
			(pts
				(xy -0.561594 -1.726946) (xy -0.053594 -2.234946) (xy -1.069594 -2.234946)
			)
			(stroke
				(width 0)
				(type default)
			)
			(fill yes)
			(layer "F.SilkS")
		)
		(fp_rect
			(start -1.524 0.7493)
			(end 1.524 -0.7493)
			(stroke
				(width 0)
				(type default)
			)
			(fill no)
			(layer "F.CrtYd")
		)
		(fp_poly
			(pts
				(xy -2.2225 1.905) (xy -2.2225 -1.905) (xy 2.2225 -1.905) (xy 2.2225 -0.7493) (xy -1.524 -0.7493)
				(xy -1.524 0.7493) (xy 1.524 0.7493) (xy 1.524 -0.7366) (xy 2.2225 -0.7366) (xy 2.2225 1.905)
			)
			(stroke
				(width 0)
				(type default)
			)
			(fill no)
			(layer "F.CrtYd")
		)
		(fp_rect
			(start -2.2225 1.905)
			(end 2.2225 -1.905)
			(stroke
				(width 0)
				(type default)
			)
			(fill no)
			(layer "F.Fab")
		)
		(pad "1" smd rect
			(at -0.5715 -0.813562)
			(size 2.286 1.143)
			(layers "F.Cu" "F.Mask" "F.Paste")
			(net "P12V_AUX")
		)
		(pad "2" smd rect
			(at -0.5715 0.813562)
			(size 2.286 1.143)
			(layers "F.Cu" "F.Mask" "F.Paste")
			(net "P12V_SENSE_TRACE")
		)
		(pad "3" smd rect
			(at 1.334008 -0.813562)
			(size 0.762 1.143)
			(layers "F.Cu" "F.Mask" "F.Paste")
			(net "SENSE+_R2")
		)
		(pad "4" smd rect
			(at 1.334008 0.813562)
			(size 0.762 1.143)
			(layers "F.Cu" "F.Mask" "F.Paste")
			(net "SENSE-_R2")
		)
		(zone
			(layer "F.Cu")
			(hatch none 0.5)
			(connect_pads
				(clearance 0)
			)
			(min_thickness 0.25)
			(keepout
				(tracks allowed)
				(vias not_allowed)
				(pads allowed)
				(copperpour not_allowed)
				(footprints allowed)
			)
			(placement
				(enabled no)
				(sheetname "")
			)
			(fill
				(thermal_gap 0.5)
				(thermal_bridge_width 0.5)
				(island_removal_mode 0)
			)
			(polygon
				(pts
					(xy 26.9875 -410.833062) (xy 27.369008 -410.833062) (xy 27.369008 -411.3403) (xy 26.9875 -411.3403)
				)
			)
		)
		(zone
			(layer "F.Cu")
			(hatch none 0.5)
			(connect_pads
				(clearance 0)
			)
			(min_thickness 0.25)
			(keepout
				(tracks not_allowed)
				(vias allowed)
				(pads allowed)
				(copperpour not_allowed)
				(footprints allowed)
			)
			(placement
				(enabled no)
				(sheetname "")
			)
			(fill
				(thermal_gap 0.5)
				(thermal_bridge_width 0.5)
				(island_removal_mode 0)
			)
			(polygon
				(pts
					(xy 26.9875 -410.833062) (xy 27.369008 -410.833062) (xy 27.369008 -411.3403) (xy 26.9875 -411.3403)
				)
			)
		)
		(zone
			(layer "F.Cu")
			(hatch none 0.5)
			(connect_pads
				(clearance 0)
			)
			(min_thickness 0.25)
			(keepout
				(tracks not_allowed)
				(vias allowed)
				(pads allowed)
				(copperpour not_allowed)
				(footprints allowed)
			)
			(placement
				(enabled no)
				(sheetname "")
			)
			(fill
				(thermal_gap 0.5)
				(thermal_bridge_width 0.5)
				(island_removal_mode 0)
			)
			(polygon
				(pts
					(xy 26.9875 -409.8417) (xy 27.369008 -409.8417) (xy 27.369008 -410.348938) (xy 26.9875 -410.348938)
				)
			)
		)
		(zone
			(layer "F.Cu")
			(hatch none 0.5)
			(connect_pads
				(clearance 0)
			)
			(min_thickness 0.25)
			(keepout
				(tracks allowed)
				(vias not_allowed)
				(pads allowed)
				(copperpour not_allowed)
				(footprints allowed)
			)
			(placement
				(enabled no)
				(sheetname "")
			)
			(fill
				(thermal_gap 0.5)
				(thermal_bridge_width 0.5)
				(island_removal_mode 0)
			)
			(polygon
				(pts
					(xy 26.9875 -409.8417) (xy 27.369008 -409.8417) (xy 27.369008 -410.348938) (xy 26.9875 -410.348938)
				)
			)
		)
	)
)
